(kicad_pcb
	(version 20260206)
	(generator "pcbnew")
	(generator_version "10.0")
	(general
		(thickness 1.6)
		(legacy_teardrops no)
	)
	(paper "A4")
	(title_block
		(title "9052_F0T_PDB_Converter_Brick_F_V03_1208_1600_OCP.brd")
		(comment 1 "Grand Teton / footprints 400-407 of 578")
	)
	(layers
		(0 "F.Cu" signal "TOP")
		(4 "In1.Cu" signal "GND")
		(6 "In2.Cu" signal "IN1")
		(8 "In3.Cu" signal "GND1")
		(10 "In4.Cu" signal "VCC")
		(12 "In5.Cu" signal "VCC1")
		(14 "In6.Cu" signal "GND2")
		(16 "In7.Cu" signal "IN2")
		(18 "In8.Cu" signal "GND3")
		(2 "B.Cu" signal "BOTTOM")
		(9 "F.Adhes" user "F.Adhesive")
		(11 "B.Adhes" user "B.Adhesive")
		(13 "F.Paste" user "Package Geometry/Pastemask Top")
		(15 "B.Paste" user "Package Geometry/Pastemask Bottom")
		(5 "F.SilkS" user "Ref Des/Silkscreen Top")
		(7 "B.SilkS" user "Ref Des/Silkscreen Bottom")
		(1 "F.Mask" user "Board Geometry/Soldermask Top")
		(3 "B.Mask" user "Board Geometry/Soldermask Bottom")
		(17 "Dwgs.User" user "User.Drawings")
		(19 "Cmts.User" user "User.Comments")
		(21 "Eco1.User" user "User.Eco1")
		(23 "Eco2.User" user "User.Eco2")
		(25 "Edge.Cuts" user "Board Geometry/Outline")
		(27 "Margin" user)
		(31 "F.CrtYd" user "Package Geometry/Place Bound Top")
		(29 "B.CrtYd" user "Package Geometry/Place Bound Bottom")
		(35 "F.Fab" user "Ref Des/Assembly Top")
		(33 "B.Fab" user "Ref Des/Assembly Bottom")
	)
	(footprint ""
		(layer "B.Cu")
		(at 229.616 -95.504 90)
		(property "Reference" "C26"
			(at 0 0 90)
			(layer "B.SilkS")
			(hide yes)
			(effects
				(font
					(size 1.27 1.27)
				)
				(justify mirror)
			)
		)
		(property "Value" ""
			(at 0 0 90)
			(layer "B.Fab")
			(effects
				(font
					(size 1.27 1.27)
				)
				(justify mirror)
			)
		)
		(duplicate_pad_numbers_are_jumpers no)
		(fp_line
			(start 2.2098 -0.9398)
			(end -2.2098 -0.9398)
			(stroke
				(width 0.1524)
				(type default)
			)
			(layer "B.SilkS")
		)
		(fp_line
			(start -2.2098 -0.9398)
			(end -2.2098 0.9398)
			(stroke
				(width 0.1524)
				(type default)
			)
			(layer "B.SilkS")
		)
		(fp_line
			(start 2.2098 0.9398)
			(end 2.2098 -0.9398)
			(stroke
				(width 0.1524)
				(type default)
			)
			(layer "B.SilkS")
		)
		(fp_line
			(start -2.2098 0.9398)
			(end 2.2098 0.9398)
			(stroke
				(width 0.1524)
				(type default)
			)
			(layer "B.SilkS")
		)
		(fp_line
			(start 1.700022 -0.899922)
			(end -1.700022 -0.899922)
			(stroke
				(width 0.1)
				(type default)
			)
			(layer "B.Fab")
		)
		(fp_line
			(start -1.700022 -0.899922)
			(end -1.700022 0.899922)
			(stroke
				(width 0.1)
				(type default)
			)
			(layer "B.Fab")
		)
		(fp_line
			(start 1.700022 0.899922)
			(end 1.700022 -0.899922)
			(stroke
				(width 0.1)
				(type default)
			)
			(layer "B.Fab")
		)
		(fp_line
			(start -1.700022 0.899922)
			(end 1.700022 0.899922)
			(stroke
				(width 0.1)
				(type default)
			)
			(layer "B.Fab")
		)
		(pad "1" smd rect
			(at 1.4732 0 90)
			(size 1.1684 1.5748)
			(layers "B.Cu" "B.Mask" "B.Paste")
			(net "P52V_HS")
		)
		(pad "2" smd rect
			(at -1.4732 0 90)
			(size 1.1684 1.5748)
			(layers "B.Cu" "B.Mask" "B.Paste")
			(net "GND")
		)
	)
	(footprint ""
		(layer "B.Cu")
		(at 234.569 -95.504 90)
		(property "Reference" "C30"
			(at 0 0 90)
			(layer "B.SilkS")
			(hide yes)
			(effects
				(font
					(size 1.27 1.27)
				)
				(justify mirror)
			)
		)
		(property "Value" ""
			(at 0 0 90)
			(layer "B.Fab")
			(effects
				(font
					(size 1.27 1.27)
				)
				(justify mirror)
			)
		)
		(duplicate_pad_numbers_are_jumpers no)
		(fp_line
			(start 2.2098 -0.9398)
			(end -2.2098 -0.9398)
			(stroke
				(width 0.1524)
				(type default)
			)
			(layer "B.SilkS")
		)
		(fp_line
			(start -2.2098 -0.9398)
			(end -2.2098 0.9398)
			(stroke
				(width 0.1524)
				(type default)
			)
			(layer "B.SilkS")
		)
		(fp_line
			(start 2.2098 0.9398)
			(end 2.2098 -0.9398)
			(stroke
				(width 0.1524)
				(type default)
			)
			(layer "B.SilkS")
		)
		(fp_line
			(start -2.2098 0.9398)
			(end 2.2098 0.9398)
			(stroke
				(width 0.1524)
				(type default)
			)
			(layer "B.SilkS")
		)
		(fp_line
			(start 1.700022 -0.899922)
			(end -1.700022 -0.899922)
			(stroke
				(width 0.1)
				(type default)
			)
			(layer "B.Fab")
		)
		(fp_line
			(start -1.700022 -0.899922)
			(end -1.700022 0.899922)
			(stroke
				(width 0.1)
				(type default)
			)
			(layer "B.Fab")
		)
		(fp_line
			(start 1.700022 0.899922)
			(end 1.700022 -0.899922)
			(stroke
				(width 0.1)
				(type default)
			)
			(layer "B.Fab")
		)
		(fp_line
			(start -1.700022 0.899922)
			(end 1.700022 0.899922)
			(stroke
				(width 0.1)
				(type default)
			)
			(layer "B.Fab")
		)
		(pad "1" smd rect
			(at 1.4732 0 90)
			(size 1.1684 1.5748)
			(layers "B.Cu" "B.Mask" "B.Paste")
			(net "P52V_HS")
		)
		(pad "2" smd rect
			(at -1.4732 0 90)
			(size 1.1684 1.5748)
			(layers "B.Cu" "B.Mask" "B.Paste")
			(net "GND")
		)
	)
	(footprint ""
		(layer "B.Cu")
		(at 96.52 -78.613)
		(property "Reference" "R176"
			(at 0 0 0)
			(layer "B.SilkS")
			(hide yes)
			(effects
				(font
					(size 1.27 1.27)
				)
				(justify mirror)
			)
		)
		(property "Value" ""
			(at 0 0 0)
			(layer "B.Fab")
			(effects
				(font
					(size 1.27 1.27)
				)
				(justify mirror)
			)
		)
		(duplicate_pad_numbers_are_jumpers no)
		(fp_line
			(start -0.7874 -0.4064)
			(end -0.7874 0.4064)
			(stroke
				(width 0.1524)
				(type default)
			)
			(layer "B.SilkS")
		)
		(fp_line
			(start -0.7874 0.4064)
			(end 0.7874 0.4064)
			(stroke
				(width 0.1524)
				(type default)
			)
			(layer "B.SilkS")
		)
		(fp_line
			(start 0.7874 -0.4064)
			(end -0.7874 -0.4064)
			(stroke
				(width 0.1524)
				(type default)
			)
			(layer "B.SilkS")
		)
		(fp_line
			(start 0.7874 0.4064)
			(end 0.7874 -0.4064)
			(stroke
				(width 0.1524)
				(type default)
			)
			(layer "B.SilkS")
		)
		(fp_line
			(start -0.67945 -0.3048)
			(end -0.67945 0.3048)
			(stroke
				(width 0.1)
				(type default)
			)
			(layer "B.Fab")
		)
		(fp_line
			(start -0.67945 0.3048)
			(end -0.120396 0.3048)
			(stroke
				(width 0.1)
				(type default)
			)
			(layer "B.Fab")
		)
		(fp_line
			(start -0.12065 -0.3048)
			(end -0.67945 -0.3048)
			(stroke
				(width 0.1)
				(type default)
			)
			(layer "B.Fab")
		)
		(fp_line
			(start -0.12065 -0.2794)
			(end -0.12065 -0.3048)
			(stroke
				(width 0.1)
				(type default)
			)
			(layer "B.Fab")
		)
		(fp_line
			(start -0.120396 0.2794)
			(end 0.12065 0.2794)
			(stroke
				(width 0.1)
				(type default)
			)
			(layer "B.Fab")
		)
		(fp_line
			(start -0.120396 0.3048)
			(end -0.120396 0.2794)
			(stroke
				(width 0.1)
				(type default)
			)
			(layer "B.Fab")
		)
		(fp_line
			(start 0.12065 -0.305054)
			(end 0.12065 -0.2794)
			(stroke
				(width 0.1)
				(type default)
			)
			(layer "B.Fab")
		)
		(fp_line
			(start 0.12065 -0.2794)
			(end -0.12065 -0.2794)
			(stroke
				(width 0.1)
				(type default)
			)
			(layer "B.Fab")
		)
		(fp_line
			(start 0.12065 0.2794)
			(end 0.12065 0.3048)
			(stroke
				(width 0.1)
				(type default)
			)
			(layer "B.Fab")
		)
		(fp_line
			(start 0.12065 0.3048)
			(end 0.67945 0.3048)
			(stroke
				(width 0.1)
				(type default)
			)
			(layer "B.Fab")
		)
		(fp_line
			(start 0.67945 -0.305054)
			(end 0.12065 -0.305054)
			(stroke
				(width 0.1)
				(type default)
			)
			(layer "B.Fab")
		)
		(fp_line
			(start 0.67945 0.3048)
			(end 0.67945 -0.305054)
			(stroke
				(width 0.1)
				(type default)
			)
			(layer "B.Fab")
		)
		(pad "1" smd circle
			(at 0.40005 0 180)
			(size 0 0)
			(layers "B.Cu" "B.Mask" "B.Paste")
			(net "P3V3_AUX")
		)
		(pad "2" smd circle
			(at -0.40005 0 180)
			(size 0 0)
			(layers "B.Cu" "B.Mask" "B.Paste")
			(net "SMB_P52V_VPDB_SCL")
		)
	)
	(footprint ""
		(layer "B.Cu")
		(at 227.203 -70.993 -90)
		(property "Reference" "C47"
			(at 0 0 90)
			(layer "B.SilkS")
			(hide yes)
			(effects
				(font
					(size 1.27 1.27)
				)
				(justify mirror)
			)
		)
		(property "Value" ""
			(at 0 0 90)
			(layer "B.Fab")
			(effects
				(font
					(size 1.27 1.27)
				)
				(justify mirror)
			)
		)
		(duplicate_pad_numbers_are_jumpers no)
		(fp_line
			(start -0.7874 0.4064)
			(end 0.7874 0.4064)
			(stroke
				(width 0.1524)
				(type default)
			)
			(layer "B.SilkS")
		)
		(fp_line
			(start 0.7874 0.4064)
			(end 0.7874 -0.4064)
			(stroke
				(width 0.1524)
				(type default)
			)
			(layer "B.SilkS")
		)
		(fp_line
			(start -0.7874 -0.4064)
			(end -0.7874 0.4064)
			(stroke
				(width 0.1524)
				(type default)
			)
			(layer "B.SilkS")
		)
		(fp_line
			(start 0.7874 -0.4064)
			(end -0.7874 -0.4064)
			(stroke
				(width 0.1524)
				(type default)
			)
			(layer "B.SilkS")
		)
		(fp_line
			(start -0.67945 0.3048)
			(end -0.120396 0.3048)
			(stroke
				(width 0.1)
				(type default)
			)
			(layer "B.Fab")
		)
		(fp_line
			(start -0.120396 0.3048)
			(end -0.120396 0.2794)
			(stroke
				(width 0.1)
				(type default)
			)
			(layer "B.Fab")
		)
		(fp_line
			(start 0.12065 0.3048)
			(end 0.67945 0.3048)
			(stroke
				(width 0.1)
				(type default)
			)
			(layer "B.Fab")
		)
		(fp_line
			(start 0.67945 0.3048)
			(end 0.67945 -0.305054)
			(stroke
				(width 0.1)
				(type default)
			)
			(layer "B.Fab")
		)
		(fp_line
			(start -0.120396 0.2794)
			(end 0.12065 0.2794)
			(stroke
				(width 0.1)
				(type default)
			)
			(layer "B.Fab")
		)
		(fp_line
			(start 0.12065 0.2794)
			(end 0.12065 0.3048)
			(stroke
				(width 0.1)
				(type default)
			)
			(layer "B.Fab")
		)
		(fp_line
			(start -0.12065 -0.2794)
			(end -0.12065 -0.3048)
			(stroke
				(width 0.1)
				(type default)
			)
			(layer "B.Fab")
		)
		(fp_line
			(start 0.12065 -0.2794)
			(end -0.12065 -0.2794)
			(stroke
				(width 0.1)
				(type default)
			)
			(layer "B.Fab")
		)
		(fp_line
			(start -0.67945 -0.3048)
			(end -0.67945 0.3048)
			(stroke
				(width 0.1)
				(type default)
			)
			(layer "B.Fab")
		)
		(fp_line
			(start -0.12065 -0.3048)
			(end -0.67945 -0.3048)
			(stroke
				(width 0.1)
				(type default)
			)
			(layer "B.Fab")
		)
		(fp_line
			(start 0.12065 -0.305054)
			(end 0.12065 -0.2794)
			(stroke
				(width 0.1)
				(type default)
			)
			(layer "B.Fab")
		)
		(fp_line
			(start 0.67945 -0.305054)
			(end 0.12065 -0.305054)
			(stroke
				(width 0.1)
				(type default)
			)
			(layer "B.Fab")
		)
		(pad "1" smd circle
			(at 0.40005 0 90)
			(size 0 0)
			(layers "B.Cu" "B.Mask" "B.Paste")
			(net "P12V_BRICK_PWRGD_R_N")
		)
		(pad "2" smd circle
			(at -0.40005 0 90)
			(size 0 0)
			(layers "B.Cu" "B.Mask" "B.Paste")
			(net "GND")
		)
	)
	(footprint ""
		(layer "B.Cu")
		(at 239.395 -95.504 90)
		(property "Reference" "C34"
			(at 0 0 90)
			(layer "B.SilkS")
			(hide yes)
			(effects
				(font
					(size 1.27 1.27)
				)
				(justify mirror)
			)
		)
		(property "Value" ""
			(at 0 0 90)
			(layer "B.Fab")
			(effects
				(font
					(size 1.27 1.27)
				)
				(justify mirror)
			)
		)
		(duplicate_pad_numbers_are_jumpers no)
		(fp_line
			(start 2.2098 -0.9398)
			(end -2.2098 -0.9398)
			(stroke
				(width 0.1524)
				(type default)
			)
			(layer "B.SilkS")
		)
		(fp_line
			(start -2.2098 -0.9398)
			(end -2.2098 0.9398)
			(stroke
				(width 0.1524)
				(type default)
			)
			(layer "B.SilkS")
		)
		(fp_line
			(start 2.2098 0.9398)
			(end 2.2098 -0.9398)
			(stroke
				(width 0.1524)
				(type default)
			)
			(layer "B.SilkS")
		)
		(fp_line
			(start -2.2098 0.9398)
			(end 2.2098 0.9398)
			(stroke
				(width 0.1524)
				(type default)
			)
			(layer "B.SilkS")
		)
		(fp_line
			(start 1.700022 -0.899922)
			(end -1.700022 -0.899922)
			(stroke
				(width 0.1)
				(type default)
			)
			(layer "B.Fab")
		)
		(fp_line
			(start -1.700022 -0.899922)
			(end -1.700022 0.899922)
			(stroke
				(width 0.1)
				(type default)
			)
			(layer "B.Fab")
		)
		(fp_line
			(start 1.700022 0.899922)
			(end 1.700022 -0.899922)
			(stroke
				(width 0.1)
				(type default)
			)
			(layer "B.Fab")
		)
		(fp_line
			(start -1.700022 0.899922)
			(end 1.700022 0.899922)
			(stroke
				(width 0.1)
				(type default)
			)
			(layer "B.Fab")
		)
		(pad "1" smd rect
			(at 1.4732 0 90)
			(size 1.1684 1.5748)
			(layers "B.Cu" "B.Mask" "B.Paste")
			(net "P52V_HS")
		)
		(pad "2" smd rect
			(at -1.4732 0 90)
			(size 1.1684 1.5748)
			(layers "B.Cu" "B.Mask" "B.Paste")
			(net "GND")
		)
	)
	(footprint ""
		(layer "B.Cu")
		(at 174.493174 -77.597 180)
		(property "Reference" "C71"
			(at 0 0 0)
			(layer "B.SilkS")
			(hide yes)
			(effects
				(font
					(size 1.27 1.27)
				)
				(justify mirror)
			)
		)
		(property "Value" ""
			(at 0 0 0)
			(layer "B.Fab")
			(effects
				(font
					(size 1.27 1.27)
				)
				(justify mirror)
			)
		)
		(duplicate_pad_numbers_are_jumpers no)
		(fp_line
			(start 0.7874 0.4064)
			(end 0.7874 -0.4064)
			(stroke
				(width 0.1524)
				(type default)
			)
			(layer "B.SilkS")
		)
		(fp_line
			(start 0.7874 -0.4064)
			(end -0.7874 -0.4064)
			(stroke
				(width 0.1524)
				(type default)
			)
			(layer "B.SilkS")
		)
		(fp_line
			(start -0.7874 0.4064)
			(end 0.7874 0.4064)
			(stroke
				(width 0.1524)
				(type default)
			)
			(layer "B.SilkS")
		)
		(fp_line
			(start -0.7874 -0.4064)
			(end -0.7874 0.4064)
			(stroke
				(width 0.1524)
				(type default)
			)
			(layer "B.SilkS")
		)
		(fp_line
			(start 0.67945 0.3048)
			(end 0.67945 -0.305054)
			(stroke
				(width 0.1)
				(type default)
			)
			(layer "B.Fab")
		)
		(fp_line
			(start 0.67945 -0.305054)
			(end 0.12065 -0.305054)
			(stroke
				(width 0.1)
				(type default)
			)
			(layer "B.Fab")
		)
		(fp_line
			(start 0.12065 0.3048)
			(end 0.67945 0.3048)
			(stroke
				(width 0.1)
				(type default)
			)
			(layer "B.Fab")
		)
		(fp_line
			(start 0.12065 0.2794)
			(end 0.12065 0.3048)
			(stroke
				(width 0.1)
				(type default)
			)
			(layer "B.Fab")
		)
		(fp_line
			(start 0.12065 -0.2794)
			(end -0.12065 -0.2794)
			(stroke
				(width 0.1)
				(type default)
			)
			(layer "B.Fab")
		)
		(fp_line
			(start 0.12065 -0.305054)
			(end 0.12065 -0.2794)
			(stroke
				(width 0.1)
				(type default)
			)
			(layer "B.Fab")
		)
		(fp_line
			(start -0.120396 0.3048)
			(end -0.120396 0.2794)
			(stroke
				(width 0.1)
				(type default)
			)
			(layer "B.Fab")
		)
		(fp_line
			(start -0.120396 0.2794)
			(end 0.12065 0.2794)
			(stroke
				(width 0.1)
				(type default)
			)
			(layer "B.Fab")
		)
		(fp_line
			(start -0.12065 -0.2794)
			(end -0.12065 -0.3048)
			(stroke
				(width 0.1)
				(type default)
			)
			(layer "B.Fab")
		)
		(fp_line
			(start -0.12065 -0.3048)
			(end -0.67945 -0.3048)
			(stroke
				(width 0.1)
				(type default)
			)
			(layer "B.Fab")
		)
		(fp_line
			(start -0.67945 0.3048)
			(end -0.120396 0.3048)
			(stroke
				(width 0.1)
				(type default)
			)
			(layer "B.Fab")
		)
		(fp_line
			(start -0.67945 -0.3048)
			(end -0.67945 0.3048)
			(stroke
				(width 0.1)
				(type default)
			)
			(layer "B.Fab")
		)
		(pad "1" smd circle
			(at 0.40005 0)
			(size 0 0)
			(layers "B.Cu" "B.Mask" "B.Paste")
			(net "SMB_P52V_VPDB_SDA")
		)
		(pad "2" smd circle
			(at -0.40005 0)
			(size 0 0)
			(layers "B.Cu" "B.Mask" "B.Paste")
			(net "GND")
		)
	)
	(footprint ""
		(layer "B.Cu")
		(at 270.129 -30.734 -90)
		(property "Reference" "C101"
			(at 0 0 90)
			(layer "B.SilkS")
			(hide yes)
			(effects
				(font
					(size 1.27 1.27)
				)
				(justify mirror)
			)
		)
		(property "Value" ""
			(at 0 0 90)
			(layer "B.Fab")
			(effects
				(font
					(size 1.27 1.27)
				)
				(justify mirror)
			)
		)
		(duplicate_pad_numbers_are_jumpers no)
		(fp_line
			(start -1.524 0.762)
			(end 1.524 0.762)
			(stroke
				(width 0.1524)
				(type default)
			)
			(layer "B.SilkS")
		)
		(fp_line
			(start 1.524 0.762)
			(end 1.524 -0.762)
			(stroke
				(width 0.1524)
				(type default)
			)
			(layer "B.SilkS")
		)
		(fp_line
			(start -1.524 -0.762)
			(end -1.524 0.762)
			(stroke
				(width 0.1524)
				(type default)
			)
			(layer "B.SilkS")
		)
		(fp_line
			(start 1.524 -0.762)
			(end -1.524 -0.762)
			(stroke
				(width 0.1524)
				(type default)
			)
			(layer "B.SilkS")
		)
		(fp_line
			(start -1.1049 0.724916)
			(end -1.1049 -0.724916)
			(stroke
				(width 0.1)
				(type default)
			)
			(layer "B.Fab")
		)
		(fp_line
			(start 1.1049 0.724916)
			(end -1.1049 0.724916)
			(stroke
				(width 0.1)
				(type default)
			)
			(layer "B.Fab")
		)
		(fp_line
			(start -1.1049 -0.724916)
			(end 1.1049 -0.724916)
			(stroke
				(width 0.1)
				(type default)
			)
			(layer "B.Fab")
		)
		(fp_line
			(start 1.1049 -0.724916)
			(end 1.1049 0.724916)
			(stroke
				(width 0.1)
				(type default)
			)
			(layer "B.Fab")
		)
		(pad "1" smd rect
			(at 0.889 0 270)
			(size 1.016 1.27)
			(layers "B.Cu" "B.Mask" "B.Paste")
			(net "P52V_HS1_EN_DELAY")
		)
		(pad "2" smd rect
			(at -0.889 0 270)
			(size 1.016 1.27)
			(layers "B.Cu" "B.Mask" "B.Paste")
			(net "GND")
		)
	)
	(footprint ""
		(layer "B.Cu")
		(at 219.583 -90.043 -90)
		(property "Reference" "R41"
			(at 0 0 90)
			(layer "B.SilkS")
			(hide yes)
			(effects
				(font
					(size 1.27 1.27)
				)
				(justify mirror)
			)
		)
		(property "Value" ""
			(at 0 0 90)
			(layer "B.Fab")
			(effects
				(font
					(size 1.27 1.27)
				)
				(justify mirror)
			)
		)
		(duplicate_pad_numbers_are_jumpers no)
		(fp_line
			(start -0.7874 0.4064)
			(end 0.7874 0.4064)
			(stroke
				(width 0.1524)
				(type default)
			)
			(layer "B.SilkS")
		)
		(fp_line
			(start 0.7874 0.4064)
			(end 0.7874 -0.4064)
			(stroke
				(width 0.1524)
				(type default)
			)
			(layer "B.SilkS")
		)
		(fp_line
			(start -0.7874 -0.4064)
			(end -0.7874 0.4064)
			(stroke
				(width 0.1524)
				(type default)
			)
			(layer "B.SilkS")
		)
		(fp_line
			(start 0.7874 -0.4064)
			(end -0.7874 -0.4064)
			(stroke
				(width 0.1524)
				(type default)
			)
			(layer "B.SilkS")
		)
		(fp_line
			(start -0.67945 0.3048)
			(end -0.120396 0.3048)
			(stroke
				(width 0.1)
				(type default)
			)
			(layer "B.Fab")
		)
		(fp_line
			(start -0.120396 0.3048)
			(end -0.120396 0.2794)
			(stroke
				(width 0.1)
				(type default)
			)
			(layer "B.Fab")
		)
		(fp_line
			(start 0.12065 0.3048)
			(end 0.67945 0.3048)
			(stroke
				(width 0.1)
				(type default)
			)
			(layer "B.Fab")
		)
		(fp_line
			(start 0.67945 0.3048)
			(end 0.67945 -0.305054)
			(stroke
				(width 0.1)
				(type default)
			)
			(layer "B.Fab")
		)
		(fp_line
			(start -0.120396 0.2794)
			(end 0.12065 0.2794)
			(stroke
				(width 0.1)
				(type default)
			)
			(layer "B.Fab")
		)
		(fp_line
			(start 0.12065 0.2794)
			(end 0.12065 0.3048)
			(stroke
				(width 0.1)
				(type default)
			)
			(layer "B.Fab")
		)
		(fp_line
			(start -0.12065 -0.2794)
			(end -0.12065 -0.3048)
			(stroke
				(width 0.1)
				(type default)
			)
			(layer "B.Fab")
		)
		(fp_line
			(start 0.12065 -0.2794)
			(end -0.12065 -0.2794)
			(stroke
				(width 0.1)
				(type default)
			)
			(layer "B.Fab")
		)
		(fp_line
			(start -0.67945 -0.3048)
			(end -0.67945 0.3048)
			(stroke
				(width 0.1)
				(type default)
			)
			(layer "B.Fab")
		)
		(fp_line
			(start -0.12065 -0.3048)
			(end -0.67945 -0.3048)
			(stroke
				(width 0.1)
				(type default)
			)
			(layer "B.Fab")
		)
		(fp_line
			(start 0.12065 -0.305054)
			(end 0.12065 -0.2794)
			(stroke
				(width 0.1)
				(type default)
			)
			(layer "B.Fab")
		)
		(fp_line
			(start 0.67945 -0.305054)
			(end 0.12065 -0.305054)
			(stroke
				(width 0.1)
				(type default)
			)
			(layer "B.Fab")
		)
		(pad "1" smd circle
			(at 0.40005 0 90)
			(size 0 0)
			(layers "B.Cu" "B.Mask" "B.Paste")
			(net "SMB_FRU_DAT")
		)
		(pad "2" smd circle
			(at -0.40005 0 90)
			(size 0 0)
			(layers "B.Cu" "B.Mask" "B.Paste")
			(net "SMB_VPDB_MISC_SDA")
		)
	)
)
